# T6G (Grand Teton) — schematic parts with pin connectivity, parts 2188–2284 of 8303; source: Cadence DE-HDL packaged netlist (pstxprt.dat, pstxnet.dat, pstchip.dat)

C6572  Q_CAP_DIFFBUS  DIFF BUS_0.22UF 6.3V 20% X6S  pkg C0201  page 297 : 1 = P5E_CPU0_P2_TX_BUF_C_DN<3> ; 2 = P5E_CPU0_P2_TX_BUF_DN<3>
C6573  Q_CAP_DIFFBUS  DIFF BUS_0.22UF 6.3V 20% X6S  pkg C0201  page 297 : 1 = P5E_CPU0_P2_TX_BUF_C_DP<4> ; 2 = P5E_CPU0_P2_TX_BUF_DP<4>
C6574  Q_CAP_DIFFBUS  DIFF BUS_0.22UF 6.3V 20% X6S  pkg C0201  page 297 : 1 = P5E_CPU0_P2_TX_BUF_C_DN<4> ; 2 = P5E_CPU0_P2_TX_BUF_DN<4>
C6575  Q_CAP_DIFFBUS  DIFF BUS_0.22UF 6.3V 20% X6S  pkg C0201  page 297 : 1 = P5E_CPU0_P2_TX_BUF_C_DP<5> ; 2 = P5E_CPU0_P2_TX_BUF_DP<5>
C6576  Q_CAP_DIFFBUS  DIFF BUS_0.22UF 6.3V 20% X6S  pkg C0201  page 297 : 1 = P5E_CPU0_P2_TX_BUF_C_DN<5> ; 2 = P5E_CPU0_P2_TX_BUF_DN<5>
C6577  Q_CAP_DIFFBUS  DIFF BUS_0.22UF 6.3V 20% X6S  pkg C0201  page 297 : 1 = P5E_CPU0_P2_TX_BUF_C_DP<6> ; 2 = P5E_CPU0_P2_TX_BUF_DP<6>
C6578  Q_CAP_DIFFBUS  DIFF BUS_0.22UF 6.3V 20% X6S  pkg C0201  page 297 : 1 = P5E_CPU0_P2_TX_BUF_C_DN<6> ; 2 = P5E_CPU0_P2_TX_BUF_DN<6>
C6579  Q_CAP_DIFFBUS  DIFF BUS_0.22UF 6.3V 20% X6S  pkg C0201  page 297 : 1 = P5E_CPU0_P2_TX_BUF_C_DP<7> ; 2 = P5E_CPU0_P2_TX_BUF_DP<7>
C6580  Q_CAP_DIFFBUS  DIFF BUS_0.22UF 6.3V 20% X6S  pkg C0201  page 297 : 1 = P5E_CPU0_P2_TX_BUF_C_DN<7> ; 2 = P5E_CPU0_P2_TX_BUF_DN<7>
C6581  Q_CAP_DIFFBUS  DIFF BUS_0.22UF 6.3V 20% X6S  pkg C0201  page 297 : 1 = P5E_CPU0_P2_TX_BUF_C_DP<8> ; 2 = P5E_CPU0_P2_TX_BUF_DP<8>
C6582  Q_CAP_DIFFBUS  DIFF BUS_0.22UF 6.3V 20% X6S  pkg C0201  page 297 : 1 = P5E_CPU0_P2_TX_BUF_C_DN<8> ; 2 = P5E_CPU0_P2_TX_BUF_DN<8>
C6583  Q_CAP_DIFFBUS  DIFF BUS_0.22UF 6.3V 20% X6S  pkg C0201  page 297 : 1 = P5E_CPU0_P2_TX_BUF_C_DP<9> ; 2 = P5E_CPU0_P2_TX_BUF_DP<9>
C6584  Q_CAP_DIFFBUS  DIFF BUS_0.22UF 6.3V 20% X6S  pkg C0201  page 297 : 1 = P5E_CPU0_P2_TX_BUF_C_DN<9> ; 2 = P5E_CPU0_P2_TX_BUF_DN<9>
C6585  Q_CAP_DIFFBUS  DIFF BUS_0.22UF 6.3V 20% X6S  pkg C0201  page 297 : 1 = P5E_CPU0_P2_TX_BUF_C_DP<10> ; 2 = P5E_CPU0_P2_TX_BUF_DP<10>
C6586  Q_CAP_DIFFBUS  DIFF BUS_0.22UF 6.3V 20% X6S  pkg C0201  page 297 : 1 = P5E_CPU0_P2_TX_BUF_C_DN<10> ; 2 = P5E_CPU0_P2_TX_BUF_DN<10>
C6587  Q_CAP_DIFFBUS  DIFF BUS_0.22UF 6.3V 20% X6S  pkg C0201  page 297 : 1 = P5E_CPU0_P2_TX_BUF_C_DP<11> ; 2 = P5E_CPU0_P2_TX_BUF_DP<11>
C6588  Q_CAP_DIFFBUS  DIFF BUS_0.22UF 6.3V 20% X6S  pkg C0201  page 297 : 1 = P5E_CPU0_P2_TX_BUF_C_DN<11> ; 2 = P5E_CPU0_P2_TX_BUF_DN<11>
C6589  Q_CAP_DIFFBUS  DIFF BUS_0.22UF 6.3V 20% X6S  pkg C0201  page 297 : 1 = P5E_CPU0_P2_TX_BUF_C_DP<12> ; 2 = P5E_CPU0_P2_TX_BUF_DP<12>
C6590  Q_CAP_DIFFBUS  DIFF BUS_0.22UF 6.3V 20% X6S  pkg C0201  page 297 : 1 = P5E_CPU0_P2_TX_BUF_C_DN<12> ; 2 = P5E_CPU0_P2_TX_BUF_DN<12>
C6591  Q_CAP_DIFFBUS  DIFF BUS_0.22UF 6.3V 20% X6S  pkg C0201  page 297 : 1 = P5E_CPU0_P2_TX_BUF_C_DP<13> ; 2 = P5E_CPU0_P2_TX_BUF_DP<13>
C6592  Q_CAP_DIFFBUS  DIFF BUS_0.22UF 6.3V 20% X6S  pkg C0201  page 297 : 1 = P5E_CPU0_P2_TX_BUF_C_DN<13> ; 2 = P5E_CPU0_P2_TX_BUF_DN<13>
C6593  Q_CAP_DIFFBUS  DIFF BUS_0.22UF 6.3V 20% X6S  pkg C0201  page 297 : 1 = P5E_CPU0_P2_TX_BUF_C_DP<14> ; 2 = P5E_CPU0_P2_TX_BUF_DP<14>
C6594  Q_CAP_DIFFBUS  DIFF BUS_0.22UF 6.3V 20% X6S  pkg C0201  page 297 : 1 = P5E_CPU0_P2_TX_BUF_C_DN<14> ; 2 = P5E_CPU0_P2_TX_BUF_DN<14>
C6595  Q_CAP_DIFFBUS  DIFF BUS_0.22UF 6.3V 20% X6S  pkg C0201  page 297 : 1 = P5E_CPU0_P2_TX_BUF_C_DP<15> ; 2 = P5E_CPU0_P2_TX_BUF_DP<15>
C6596  Q_CAP_DIFFBUS  DIFF BUS_0.22UF 6.3V 20% X6S  pkg C0201  page 297 : 1 = P5E_CPU0_P2_TX_BUF_C_DN<15> ; 2 = P5E_CPU0_P2_TX_BUF_DN<15>
C6597  Q_CAP_DIFFBUS  DIFF BUS_0.22UF 6.3V 20% X6S  pkg C0201  page 308 : 1 = P5E_CPU0_P3_TX_BUF_C_DP<0> ; 2 = P5E_CPU0_P3_TX_BUF_DP<0>
C6598  Q_CAP_DIFFBUS  DIFF BUS_0.22UF 6.3V 20% X6S  pkg C0201  page 308 : 1 = P5E_CPU0_P3_TX_BUF_C_DN<0> ; 2 = P5E_CPU0_P3_TX_BUF_DN<0>
C6599  Q_CAP_DIFFBUS  DIFF BUS_0.22UF 6.3V 20% X6S  pkg C0201  page 308 : 1 = P5E_CPU0_P3_TX_BUF_C_DP<1> ; 2 = P5E_CPU0_P3_TX_BUF_DP<1>
C6600  Q_CAP_DIFFBUS  DIFF BUS_0.22UF 6.3V 20% X6S  pkg C0201  page 308 : 1 = P5E_CPU0_P3_TX_BUF_C_DN<1> ; 2 = P5E_CPU0_P3_TX_BUF_DN<1>
C6601  Q_CAP_DIFFBUS  DIFF BUS_0.22UF 6.3V 20% X6S  pkg C0201  page 308 : 1 = P5E_CPU0_P3_TX_BUF_C_DP<2> ; 2 = P5E_CPU0_P3_TX_BUF_DP<2>
C6602  Q_CAP_DIFFBUS  DIFF BUS_0.22UF 6.3V 20% X6S  pkg C0201  page 308 : 1 = P5E_CPU0_P3_TX_BUF_C_DN<2> ; 2 = P5E_CPU0_P3_TX_BUF_DN<2>
C6603  Q_CAP_DIFFBUS  DIFF BUS_0.22UF 6.3V 20% X6S  pkg C0201  page 308 : 1 = P5E_CPU0_P3_TX_BUF_C_DP<3> ; 2 = P5E_CPU0_P3_TX_BUF_DP<3>
C6604  Q_CAP_DIFFBUS  DIFF BUS_0.22UF 6.3V 20% X6S  pkg C0201  page 308 : 1 = P5E_CPU0_P3_TX_BUF_C_DN<3> ; 2 = P5E_CPU0_P3_TX_BUF_DN<3>
C6605  Q_CAP_DIFFBUS  DIFF BUS_0.22UF 6.3V 20% X6S  pkg C0201  page 308 : 1 = P5E_CPU0_P3_TX_BUF_C_DP<4> ; 2 = P5E_CPU0_P3_TX_BUF_DP<4>
C6606  Q_CAP_DIFFBUS  DIFF BUS_0.22UF 6.3V 20% X6S  pkg C0201  page 308 : 1 = P5E_CPU0_P3_TX_BUF_C_DN<4> ; 2 = P5E_CPU0_P3_TX_BUF_DN<4>
C6607  Q_CAP_DIFFBUS  DIFF BUS_0.22UF 6.3V 20% X6S  pkg C0201  page 308 : 1 = P5E_CPU0_P3_TX_BUF_C_DP<5> ; 2 = P5E_CPU0_P3_TX_BUF_DP<5>
C6608  Q_CAP_DIFFBUS  DIFF BUS_0.22UF 6.3V 20% X6S  pkg C0201  page 308 : 1 = P5E_CPU0_P3_TX_BUF_C_DN<5> ; 2 = P5E_CPU0_P3_TX_BUF_DN<5>
C6609  Q_CAP_DIFFBUS  DIFF BUS_0.22UF 6.3V 20% X6S  pkg C0201  page 308 : 1 = P5E_CPU0_P3_TX_BUF_C_DP<6> ; 2 = P5E_CPU0_P3_TX_BUF_DP<6>
C6610  Q_CAP_DIFFBUS  DIFF BUS_0.22UF 6.3V 20% X6S  pkg C0201  page 308 : 1 = P5E_CPU0_P3_TX_BUF_C_DN<6> ; 2 = P5E_CPU0_P3_TX_BUF_DN<6>
C6611  Q_CAP_DIFFBUS  DIFF BUS_0.22UF 6.3V 20% X6S  pkg C0201  page 308 : 1 = P5E_CPU0_P3_TX_BUF_C_DP<7> ; 2 = P5E_CPU0_P3_TX_BUF_DP<7>
C6612  Q_CAP_DIFFBUS  DIFF BUS_0.22UF 6.3V 20% X6S  pkg C0201  page 308 : 1 = P5E_CPU0_P3_TX_BUF_C_DN<7> ; 2 = P5E_CPU0_P3_TX_BUF_DN<7>
C6613  Q_CAP_DIFFBUS  DIFF BUS_0.22UF 6.3V 20% X6S  pkg C0201  page 308 : 1 = P5E_CPU0_P3_TX_BUF_C_DP<8> ; 2 = P5E_CPU0_P3_TX_BUF_DP<8>
C6614  Q_CAP_DIFFBUS  DIFF BUS_0.22UF 6.3V 20% X6S  pkg C0201  page 308 : 1 = P5E_CPU0_P3_TX_BUF_C_DN<8> ; 2 = P5E_CPU0_P3_TX_BUF_DN<8>
C6615  Q_CAP_DIFFBUS  DIFF BUS_0.22UF 6.3V 20% X6S  pkg C0201  page 308 : 1 = P5E_CPU0_P3_TX_BUF_C_DP<9> ; 2 = P5E_CPU0_P3_TX_BUF_DP<9>
C6616  Q_CAP_DIFFBUS  DIFF BUS_0.22UF 6.3V 20% X6S  pkg C0201  page 308 : 1 = P5E_CPU0_P3_TX_BUF_C_DN<9> ; 2 = P5E_CPU0_P3_TX_BUF_DN<9>
C6617  Q_CAP_DIFFBUS  DIFF BUS_0.22UF 6.3V 20% X6S  pkg C0201  page 308 : 1 = P5E_CPU0_P3_TX_BUF_C_DP<10> ; 2 = P5E_CPU0_P3_TX_BUF_DP<10>
C6618  Q_CAP_DIFFBUS  DIFF BUS_0.22UF 6.3V 20% X6S  pkg C0201  page 308 : 1 = P5E_CPU0_P3_TX_BUF_C_DN<10> ; 2 = P5E_CPU0_P3_TX_BUF_DN<10>
C6619  Q_CAP_DIFFBUS  DIFF BUS_0.22UF 6.3V 20% X6S  pkg C0201  page 308 : 1 = P5E_CPU0_P3_TX_BUF_C_DP<11> ; 2 = P5E_CPU0_P3_TX_BUF_DP<11>
C6620  Q_CAP_DIFFBUS  DIFF BUS_0.22UF 6.3V 20% X6S  pkg C0201  page 308 : 1 = P5E_CPU0_P3_TX_BUF_C_DN<11> ; 2 = P5E_CPU0_P3_TX_BUF_DN<11>
C6621  Q_CAP_DIFFBUS  DIFF BUS_0.22UF 6.3V 20% X6S  pkg C0201  page 308 : 1 = P5E_CPU0_P3_TX_BUF_C_DP<12> ; 2 = P5E_CPU0_P3_TX_BUF_DP<12>
C6622  Q_CAP_DIFFBUS  DIFF BUS_0.22UF 6.3V 20% X6S  pkg C0201  page 308 : 1 = P5E_CPU0_P3_TX_BUF_C_DN<12> ; 2 = P5E_CPU0_P3_TX_BUF_DN<12>
C6623  Q_CAP_DIFFBUS  DIFF BUS_0.22UF 6.3V 20% X6S  pkg C0201  page 308 : 1 = P5E_CPU0_P3_TX_BUF_C_DP<13> ; 2 = P5E_CPU0_P3_TX_BUF_DP<13>
C6624  Q_CAP_DIFFBUS  DIFF BUS_0.22UF 6.3V 20% X6S  pkg C0201  page 308 : 1 = P5E_CPU0_P3_TX_BUF_C_DN<13> ; 2 = P5E_CPU0_P3_TX_BUF_DN<13>
C6625  Q_CAP_DIFFBUS  DIFF BUS_0.22UF 6.3V 20% X6S  pkg C0201  page 308 : 1 = P5E_CPU0_P3_TX_BUF_C_DP<14> ; 2 = P5E_CPU0_P3_TX_BUF_DP<14>
C6626  Q_CAP_DIFFBUS  DIFF BUS_0.22UF 6.3V 20% X6S  pkg C0201  page 308 : 1 = P5E_CPU0_P3_TX_BUF_C_DN<14> ; 2 = P5E_CPU0_P3_TX_BUF_DN<14>
C6627  Q_CAP_DIFFBUS  DIFF BUS_0.22UF 6.3V 20% X6S  pkg C0201  page 308 : 1 = P5E_CPU0_P3_TX_BUF_C_DP<15> ; 2 = P5E_CPU0_P3_TX_BUF_DP<15>
C6628  Q_CAP_DIFFBUS  DIFF BUS_0.22UF 6.3V 20% X6S  pkg C0201  page 308 : 1 = P5E_CPU0_P3_TX_BUF_C_DN<15> ; 2 = P5E_CPU0_P3_TX_BUF_DN<15>
C6629  Q_CAP_DIFFBUS  DIFF BUS_0.22UF 6.3V 20% X6S  pkg C0201  page 319 : 1 = P5E_CPU1_P0_TX_BUF_C_DP<0> ; 2 = P5E_CPU1_P0_TX_BUF_DP<0>
C6630  Q_CAP_DIFFBUS  DIFF BUS_0.22UF 6.3V 20% X6S  pkg C0201  page 319 : 1 = P5E_CPU1_P0_TX_BUF_C_DN<0> ; 2 = P5E_CPU1_P0_TX_BUF_DN<0>
C6631  Q_CAP_DIFFBUS  DIFF BUS_0.22UF 6.3V 20% X6S  pkg C0201  page 319 : 1 = P5E_CPU1_P0_TX_BUF_C_DP<1> ; 2 = P5E_CPU1_P0_TX_BUF_DP<1>
C6632  Q_CAP_DIFFBUS  DIFF BUS_0.22UF 6.3V 20% X6S  pkg C0201  page 319 : 1 = P5E_CPU1_P0_TX_BUF_C_DN<1> ; 2 = P5E_CPU1_P0_TX_BUF_DN<1>
C6633  Q_CAP_DIFFBUS  DIFF BUS_0.22UF 6.3V 20% X6S  pkg C0201  page 319 : 1 = P5E_CPU1_P0_TX_BUF_C_DP<2> ; 2 = P5E_CPU1_P0_TX_BUF_DP<2>
C6634  Q_CAP_DIFFBUS  DIFF BUS_0.22UF 6.3V 20% X6S  pkg C0201  page 319 : 1 = P5E_CPU1_P0_TX_BUF_C_DN<2> ; 2 = P5E_CPU1_P0_TX_BUF_DN<2>
C6635  Q_CAP_DIFFBUS  DIFF BUS_0.22UF 6.3V 20% X6S  pkg C0201  page 319 : 1 = P5E_CPU1_P0_TX_BUF_C_DP<3> ; 2 = P5E_CPU1_P0_TX_BUF_DP<3>
C6636  Q_CAP_DIFFBUS  DIFF BUS_0.22UF 6.3V 20% X6S  pkg C0201  page 319 : 1 = P5E_CPU1_P0_TX_BUF_C_DN<3> ; 2 = P5E_CPU1_P0_TX_BUF_DN<3>
C6637  Q_CAP_DIFFBUS  DIFF BUS_0.22UF 6.3V 20% X6S  pkg C0201  page 319 : 1 = P5E_CPU1_P0_TX_BUF_C_DP<4> ; 2 = P5E_CPU1_P0_TX_BUF_DP<4>
C6638  Q_CAP_DIFFBUS  DIFF BUS_0.22UF 6.3V 20% X6S  pkg C0201  page 319 : 1 = P5E_CPU1_P0_TX_BUF_C_DN<4> ; 2 = P5E_CPU1_P0_TX_BUF_DN<4>
C6639  Q_CAP_DIFFBUS  DIFF BUS_0.22UF 6.3V 20% X6S  pkg C0201  page 319 : 1 = P5E_CPU1_P0_TX_BUF_C_DP<5> ; 2 = P5E_CPU1_P0_TX_BUF_DP<5>
C6640  Q_CAP_DIFFBUS  DIFF BUS_0.22UF 6.3V 20% X6S  pkg C0201  page 319 : 1 = P5E_CPU1_P0_TX_BUF_C_DN<5> ; 2 = P5E_CPU1_P0_TX_BUF_DN<5>
C6641  Q_CAP_DIFFBUS  DIFF BUS_0.22UF 6.3V 20% X6S  pkg C0201  page 319 : 1 = P5E_CPU1_P0_TX_BUF_C_DP<6> ; 2 = P5E_CPU1_P0_TX_BUF_DP<6>
C6642  Q_CAP_DIFFBUS  DIFF BUS_0.22UF 6.3V 20% X6S  pkg C0201  page 319 : 1 = P5E_CPU1_P0_TX_BUF_C_DN<6> ; 2 = P5E_CPU1_P0_TX_BUF_DN<6>
C6643  Q_CAP_DIFFBUS  DIFF BUS_0.22UF 6.3V 20% X6S  pkg C0201  page 319 : 1 = P5E_CPU1_P0_TX_BUF_C_DP<7> ; 2 = P5E_CPU1_P0_TX_BUF_DP<7>
C6644  Q_CAP_DIFFBUS  DIFF BUS_0.22UF 6.3V 20% X6S  pkg C0201  page 319 : 1 = P5E_CPU1_P0_TX_BUF_C_DN<7> ; 2 = P5E_CPU1_P0_TX_BUF_DN<7>
C6645  Q_CAP_DIFFBUS  DIFF BUS_0.22UF 6.3V 20% X6S  pkg C0201  page 319 : 1 = P5E_CPU1_P0_TX_BUF_C_DP<8> ; 2 = P5E_CPU1_P0_TX_BUF_DP<8>
C6646  Q_CAP_DIFFBUS  DIFF BUS_0.22UF 6.3V 20% X6S  pkg C0201  page 319 : 1 = P5E_CPU1_P0_TX_BUF_C_DN<8> ; 2 = P5E_CPU1_P0_TX_BUF_DN<8>
C6647  Q_CAP_DIFFBUS  DIFF BUS_0.22UF 6.3V 20% X6S  pkg C0201  page 319 : 1 = P5E_CPU1_P0_TX_BUF_C_DP<9> ; 2 = P5E_CPU1_P0_TX_BUF_DP<9>
C6648  Q_CAP_DIFFBUS  DIFF BUS_0.22UF 6.3V 20% X6S  pkg C0201  page 319 : 1 = P5E_CPU1_P0_TX_BUF_C_DN<9> ; 2 = P5E_CPU1_P0_TX_BUF_DN<9>
C6649  Q_CAP_DIFFBUS  DIFF BUS_0.22UF 6.3V 20% X6S  pkg C0201  page 319 : 1 = P5E_CPU1_P0_TX_BUF_C_DP<10> ; 2 = P5E_CPU1_P0_TX_BUF_DP<10>
C6650  Q_CAP_DIFFBUS  DIFF BUS_0.22UF 6.3V 20% X6S  pkg C0201  page 319 : 1 = P5E_CPU1_P0_TX_BUF_C_DN<10> ; 2 = P5E_CPU1_P0_TX_BUF_DN<10>
C6651  Q_CAP_DIFFBUS  DIFF BUS_0.22UF 6.3V 20% X6S  pkg C0201  page 319 : 1 = P5E_CPU1_P0_TX_BUF_C_DP<11> ; 2 = P5E_CPU1_P0_TX_BUF_DP<11>
C6652  Q_CAP_DIFFBUS  DIFF BUS_0.22UF 6.3V 20% X6S  pkg C0201  page 319 : 1 = P5E_CPU1_P0_TX_BUF_C_DN<11> ; 2 = P5E_CPU1_P0_TX_BUF_DN<11>
C6653  Q_CAP_DIFFBUS  DIFF BUS_0.22UF 6.3V 20% X6S  pkg C0201  page 319 : 1 = P5E_CPU1_P0_TX_BUF_C_DP<12> ; 2 = P5E_CPU1_P0_TX_BUF_DP<12>
C6654  Q_CAP_DIFFBUS  DIFF BUS_0.22UF 6.3V 20% X6S  pkg C0201  page 319 : 1 = P5E_CPU1_P0_TX_BUF_C_DN<12> ; 2 = P5E_CPU1_P0_TX_BUF_DN<12>
C6655  Q_CAP_DIFFBUS  DIFF BUS_0.22UF 6.3V 20% X6S  pkg C0201  page 319 : 1 = P5E_CPU1_P0_TX_BUF_C_DP<13> ; 2 = P5E_CPU1_P0_TX_BUF_DP<13>
C6656  Q_CAP_DIFFBUS  DIFF BUS_0.22UF 6.3V 20% X6S  pkg C0201  page 319 : 1 = P5E_CPU1_P0_TX_BUF_C_DN<13> ; 2 = P5E_CPU1_P0_TX_BUF_DN<13>
C6657  Q_CAP_DIFFBUS  DIFF BUS_0.22UF 6.3V 20% X6S  pkg C0201  page 319 : 1 = P5E_CPU1_P0_TX_BUF_C_DP<14> ; 2 = P5E_CPU1_P0_TX_BUF_DP<14>
C6658  Q_CAP_DIFFBUS  DIFF BUS_0.22UF 6.3V 20% X6S  pkg C0201  page 319 : 1 = P5E_CPU1_P0_TX_BUF_C_DN<14> ; 2 = P5E_CPU1_P0_TX_BUF_DN<14>
C6659  Q_CAP_DIFFBUS  DIFF BUS_0.22UF 6.3V 20% X6S  pkg C0201  page 319 : 1 = P5E_CPU1_P0_TX_BUF_C_DP<15> ; 2 = P5E_CPU1_P0_TX_BUF_DP<15>
C6660  Q_CAP_DIFFBUS  DIFF BUS_0.22UF 6.3V 20% X6S  pkg C0201  page 319 : 1 = P5E_CPU1_P0_TX_BUF_C_DN<15> ; 2 = P5E_CPU1_P0_TX_BUF_DN<15>
C6661  Q_CAP_DIFFBUS  DIFF BUS_0.22UF 6.3V 20% X6S  pkg C0201  page 330 : 1 = P5E_CPU1_P1_TX_BUF_C_DP<0> ; 2 = P5E_CPU1_P1_TX_BUF_DP<0>
C6662  Q_CAP_DIFFBUS  DIFF BUS_0.22UF 6.3V 20% X6S  pkg C0201  page 330 : 1 = P5E_CPU1_P1_TX_BUF_C_DN<0> ; 2 = P5E_CPU1_P1_TX_BUF_DN<0>
C6663  Q_CAP_DIFFBUS  DIFF BUS_0.22UF 6.3V 20% X6S  pkg C0201  page 330 : 1 = P5E_CPU1_P1_TX_BUF_C_DP<1> ; 2 = P5E_CPU1_P1_TX_BUF_DP<1>
C6664  Q_CAP_DIFFBUS  DIFF BUS_0.22UF 6.3V 20% X6S  pkg C0201  page 330 : 1 = P5E_CPU1_P1_TX_BUF_C_DN<1> ; 2 = P5E_CPU1_P1_TX_BUF_DN<1>
C6665  Q_CAP_DIFFBUS  DIFF BUS_0.22UF 6.3V 20% X6S  pkg C0201  page 330 : 1 = P5E_CPU1_P1_TX_BUF_C_DP<2> ; 2 = P5E_CPU1_P1_TX_BUF_DP<2>
C6666  Q_CAP_DIFFBUS  DIFF BUS_0.22UF 6.3V 20% X6S  pkg C0201  page 330 : 1 = P5E_CPU1_P1_TX_BUF_C_DN<2> ; 2 = P5E_CPU1_P1_TX_BUF_DN<2>
C6667  Q_CAP_DIFFBUS  DIFF BUS_0.22UF 6.3V 20% X6S  pkg C0201  page 330 : 1 = P5E_CPU1_P1_TX_BUF_C_DP<3> ; 2 = P5E_CPU1_P1_TX_BUF_DP<3>
C6668  Q_CAP_DIFFBUS  DIFF BUS_0.22UF 6.3V 20% X6S  pkg C0201  page 330 : 1 = P5E_CPU1_P1_TX_BUF_C_DN<3> ; 2 = P5E_CPU1_P1_TX_BUF_DN<3>
